# BASEBOARD_FAB2 (Tioga Pass) — schematic netlist excerpt (pin names and nets, part order shuffled) for the footprints in the layout excerpt that follows; sources: Cadence DE-HDL packaged netlist, KiCad conversion of Wiwynn_Tioga_Pass_MB.brd

R6B2  RES  100.0 1% CHIP  pkg 0402  page 21 : A = PVCCIO_CPU0 ; B = SVID_DIO1_CPU0_R
R2N27  RES  4.75K 1% CHIP  pkg 0402  page 157 : A = P3V3 ; B = FM_BMC_NMI_N
R7F24  RES  22.1 1.0% CHIP  pkg 0402  page 215 : A = PWRGD_PVDDQ_ABC_R ; B = PWRGD_PVDDQ_ABC

(kicad_pcb
	(version 20260206)
	(generator "pcbnew")
	(generator_version "10.0")
	(general
		(thickness 1.6)
		(legacy_teardrops no)
	)
	(paper "A4")
	(title_block
		(title "Wiwynn_Tioga_Pass_MB.brd")
		(comment 1 "Tioga Pass / footprints 768-770 of 4770")
	)
	(layers
		(0 "F.Cu" signal "TOP")
		(4 "In1.Cu" signal "L2GND")
		(6 "In2.Cu" signal "L3")
		(8 "In3.Cu" signal "L4GND")
		(10 "In4.Cu" signal "L5")
		(12 "In5.Cu" signal "L6GND")
		(14 "In6.Cu" signal "L7VCC")
		(16 "In7.Cu" signal "L8VCC")
		(18 "In8.Cu" signal "L9GND")
		(20 "In9.Cu" signal "L10")
		(22 "In10.Cu" signal "L11GND")
		(24 "In11.Cu" signal "L12")
		(26 "In12.Cu" signal "L13GND")
		(2 "B.Cu" signal "BOTTOM")
		(9 "F.Adhes" user "F.Adhesive")
		(11 "B.Adhes" user "B.Adhesive")
		(13 "F.Paste" user "Package Geometry/Pastemask Top")
		(15 "B.Paste" user "Package Geometry/Pastemask Bottom")
		(5 "F.SilkS" user "Ref Des/Silkscreen Top")
		(7 "B.SilkS" user "Ref Des/Silkscreen Bottom")
		(1 "F.Mask" user "Board Geometry/Soldermask Top")
		(3 "B.Mask" user "Board Geometry/Soldermask Bottom")
		(17 "Dwgs.User" user "User.Drawings")
		(19 "Cmts.User" user "User.Comments")
		(21 "Eco1.User" user "User.Eco1")
		(23 "Eco2.User" user "User.Eco2")
		(25 "Edge.Cuts" user "Board Geometry/Outline")
		(27 "Margin" user)
		(31 "F.CrtYd" user "Package Geometry/Place Bound Top")
		(29 "B.CrtYd" user "Package Geometry/Place Bound Bottom")
		(35 "F.Fab" user "Ref Des/Assembly Top")
		(33 "B.Fab" user "Ref Des/Assembly Bottom")
	)
	(footprint ""
		(layer "F.Cu")
		(at 396.367 -88.2015)
		(property "Reference" "R2N27"
			(at 0 0 0)
			(layer "F.SilkS")
			(hide yes)
			(effects
				(font
					(size 1.27 1.27)
				)
			)
		)
		(property "Value" ""
			(at 0 0 0)
			(layer "F.Fab")
			(effects
				(font
					(size 1.27 1.27)
				)
			)
		)
		(duplicate_pad_numbers_are_jumpers no)
		(fp_poly
			(pts
				(xy -0.2794 -0.1016) (xy 0.2794 -0.1016) (xy 0.2794 0.9906) (xy -0.2794 0.9906)
			)
			(stroke
				(width 0)
				(type default)
			)
			(fill no)
			(layer "F.CrtYd")
		)
		(fp_line
			(start -0.2794 -0.1016)
			(end -0.2794 0.9906)
			(stroke
				(width 0.1)
				(type default)
			)
			(layer "F.Fab")
		)
		(fp_line
			(start -0.2794 0.9906)
			(end 0.2794 0.9906)
			(stroke
				(width 0.1)
				(type default)
			)
			(layer "F.Fab")
		)
		(fp_line
			(start 0.2794 -0.1016)
			(end -0.2794 -0.1016)
			(stroke
				(width 0.1)
				(type default)
			)
			(layer "F.Fab")
		)
		(fp_line
			(start 0.2794 0.9906)
			(end 0.2794 -0.1016)
			(stroke
				(width 0.1)
				(type default)
			)
			(layer "F.Fab")
		)
		(pad "1" smd rect
			(at 0 0)
			(size 0.508 0.508)
			(layers "F.Cu" "F.Mask" "F.Paste")
			(net "P3V3")
		)
		(pad "2" smd rect
			(at 0 0.889)
			(size 0.508 0.508)
			(layers "F.Cu" "F.Mask" "F.Paste")
			(net "FM_BMC_NMI_N")
		)
		(zone
			(layer "F.Cu")
			(hatch none 0.5)
			(connect_pads
				(clearance 0)
			)
			(min_thickness 0.25)
			(keepout
				(tracks allowed)
				(vias not_allowed)
				(pads allowed)
				(copperpour not_allowed)
				(footprints allowed)
			)
			(placement
				(enabled no)
				(sheetname "")
			)
			(fill
				(thermal_gap 0.5)
				(thermal_bridge_width 0.5)
				(island_removal_mode 0)
			)
			(polygon
				(pts
					(xy 396.113 -87.9475) (xy 396.621 -87.9475) (xy 396.621 -87.5665) (xy 396.113 -87.5665)
				)
			)
		)
		(zone
			(layer "F.Cu")
			(hatch none 0.5)
			(connect_pads
				(clearance 0)
			)
			(min_thickness 0.25)
			(keepout
				(tracks not_allowed)
				(vias allowed)
				(pads allowed)
				(copperpour not_allowed)
				(footprints allowed)
			)
			(placement
				(enabled no)
				(sheetname "")
			)
			(fill
				(thermal_gap 0.5)
				(thermal_bridge_width 0.5)
				(island_removal_mode 0)
			)
			(polygon
				(pts
					(xy 396.113 -87.5665) (xy 396.621 -87.5665) (xy 396.621 -87.9475) (xy 396.113 -87.9475)
				)
			)
		)
	)
	(footprint ""
		(layer "F.Cu")
		(at 342.265 -19.558 180)
		(property "Reference" "R7F24"
			(at 0 0 180)
			(layer "F.SilkS")
			(hide yes)
			(effects
				(font
					(size 1.27 1.27)
				)
			)
		)
		(property "Value" ""
			(at 0 0 180)
			(layer "F.Fab")
			(effects
				(font
					(size 1.27 1.27)
				)
			)
		)
		(duplicate_pad_numbers_are_jumpers no)
		(fp_rect
			(start 0.2794 -0.1016)
			(end -0.2794 0.9906)
			(stroke
				(width 0)
				(type default)
			)
			(fill no)
			(layer "F.CrtYd")
		)
		(fp_line
			(start 0.2794 0.9906)
			(end 0.2794 -0.1016)
			(stroke
				(width 0.1)
				(type default)
			)
			(layer "F.Fab")
		)
		(fp_line
			(start 0.2794 -0.1016)
			(end -0.2794 -0.1016)
			(stroke
				(width 0.1)
				(type default)
			)
			(layer "F.Fab")
		)
		(fp_line
			(start -0.2794 0.9906)
			(end 0.2794 0.9906)
			(stroke
				(width 0.1)
				(type default)
			)
			(layer "F.Fab")
		)
		(fp_line
			(start -0.2794 -0.1016)
			(end -0.2794 0.9906)
			(stroke
				(width 0.1)
				(type default)
			)
			(layer "F.Fab")
		)
		(pad "1" smd rect
			(at 0 0 180)
			(size 0.508 0.508)
			(layers "F.Cu" "F.Mask" "F.Paste")
			(net "PWRGD_PVDDQ_ABC_R")
		)
		(pad "2" smd rect
			(at 0 0.889 180)
			(size 0.508 0.508)
			(layers "F.Cu" "F.Mask" "F.Paste")
			(net "PWRGD_PVDDQ_ABC")
		)
		(zone
			(layer "F.Cu")
			(hatch none 0.5)
			(connect_pads
				(clearance 0)
			)
			(min_thickness 0.25)
			(keepout
				(tracks not_allowed)
				(vias allowed)
				(pads allowed)
				(copperpour not_allowed)
				(footprints allowed)
			)
			(placement
				(enabled no)
				(sheetname "")
			)
			(fill
				(thermal_gap 0.5)
				(thermal_bridge_width 0.5)
				(island_removal_mode 0)
			)
			(polygon
				(pts
					(xy 342.011 -19.812) (xy 342.519 -19.812) (xy 342.519 -20.193) (xy 342.011 -20.193)
				)
			)
		)
		(zone
			(layer "F.Cu")
			(hatch none 0.5)
			(connect_pads
				(clearance 0)
			)
			(min_thickness 0.25)
			(keepout
				(tracks allowed)
				(vias not_allowed)
				(pads allowed)
				(copperpour not_allowed)
				(footprints allowed)
			)
			(placement
				(enabled no)
				(sheetname "")
			)
			(fill
				(thermal_gap 0.5)
				(thermal_bridge_width 0.5)
				(island_removal_mode 0)
			)
			(polygon
				(pts
					(xy 342.011 -19.812) (xy 342.519 -19.812) (xy 342.519 -20.193) (xy 342.011 -20.193)
				)
			)
		)
	)
	(footprint ""
		(layer "F.Cu")
		(at 323.98716 -131.31546)
		(property "Reference" "R6B2"
			(at 0 0 0)
			(layer "F.SilkS")
			(hide yes)
			(effects
				(font
					(size 1.27 1.27)
				)
			)
		)
		(property "Value" ""
			(at 0 0 0)
			(layer "F.Fab")
			(effects
				(font
					(size 1.27 1.27)
				)
			)
		)
		(duplicate_pad_numbers_are_jumpers no)
		(fp_poly
			(pts
				(xy -0.2794 -0.1016) (xy 0.2794 -0.1016) (xy 0.2794 0.9906) (xy -0.2794 0.9906)
			)
			(stroke
				(width 0)
				(type default)
			)
			(fill no)
			(layer "F.CrtYd")
		)
		(fp_line
			(start -0.2794 -0.1016)
			(end -0.2794 0.9906)
			(stroke
				(width 0.1)
				(type default)
			)
			(layer "F.Fab")
		)
		(fp_line
			(start -0.2794 0.9906)
			(end 0.2794 0.9906)
			(stroke
				(width 0.1)
				(type default)
			)
			(layer "F.Fab")
		)
		(fp_line
			(start 0.2794 -0.1016)
			(end -0.2794 -0.1016)
			(stroke
				(width 0.1)
				(type default)
			)
			(layer "F.Fab")
		)
		(fp_line
			(start 0.2794 0.9906)
			(end 0.2794 -0.1016)
			(stroke
				(width 0.1)
				(type default)
			)
			(layer "F.Fab")
		)
		(pad "1" smd rect
			(at 0 0)
			(size 0.508 0.508)
			(layers "F.Cu" "F.Mask" "F.Paste")
			(net "PVCCIO_CPU0")
		)
		(pad "2" smd rect
			(at 0 0.889)
			(size 0.508 0.508)
			(layers "F.Cu" "F.Mask" "F.Paste")
			(net "SVID_DIO1_CPU0_R")
		)
		(zone
			(layer "F.Cu")
			(hatch none 0.5)
			(connect_pads
				(clearance 0)
			)
			(min_thickness 0.25)
			(keepout
				(tracks allowed)
				(vias not_allowed)
				(pads allowed)
				(copperpour not_allowed)
				(footprints allowed)
			)
			(placement
				(enabled no)
				(sheetname "")
			)
			(fill
				(thermal_gap 0.5)
				(thermal_bridge_width 0.5)
				(island_removal_mode 0)
			)
			(polygon
				(pts
					(xy 323.73316 -131.06146) (xy 324.24116 -131.06146) (xy 324.24116 -130.68046) (xy 323.73316 -130.68046)
				)
			)
		)
		(zone
			(layer "F.Cu")
			(hatch none 0.5)
			(connect_pads
				(clearance 0)
			)
			(min_thickness 0.25)
			(keepout
				(tracks not_allowed)
				(vias allowed)
				(pads allowed)
				(copperpour not_allowed)
				(footprints allowed)
			)
			(placement
				(enabled no)
				(sheetname "")
			)
			(fill
				(thermal_gap 0.5)
				(thermal_bridge_width 0.5)
				(island_removal_mode 0)
			)
			(polygon
				(pts
					(xy 323.73316 -130.68046) (xy 324.24116 -130.68046) (xy 324.24116 -131.06146) (xy 323.73316 -131.06146)
				)
			)
		)
	)
)
